FILE_TYPE = CONNECTIVITY;
{Allegro Design Entry HDL 16.6-p007 (v16-6-112F) 10/10/2012}
"PAGE_NUMBER" = 173;
0"NC";
1"SATA6G_PCH_PCIE_UP_SATA_TXP<7:0>";
2"SATA6G_PCH_PCIE_UP_SATA_RXN<7:0>";
3"SATA6G_PCH_PCIE_UP_SATA_RXP<7:0>";
4"SATA6G_PCH_PCIE_UP_SATA_TXN<7:0>";
5"GND\g";
6"GND\g";
7"P3V3\g";
8"P3V3\g";
9"GND\g";
10"GND\g";
11"SATA6G_P4_TX_C_DP";
12"SATA6G_P7_TX_C_DN";
13"SATA6G_P7_RX_C_DP";
14"PD_SATA1_CONTROLLER_TYPE_R";
15"SATA6G_P1_RX_C_DN";
16"SATA6G_PCH_PCIE_UP_SATA_TXN<0>";
17"SATA6G_PCH_PCIE_UP_SATA_TXN<1>";
18"SATA6G_PCH_PCIE_UP_SATA_TXP<0>";
19"SATA6G_PCH_PCIE_UP_SATA_TXN<2>";
20"SATA6G_PCH_PCIE_UP_SATA_TXN<3>";
21"SATA6G_PCH_PCIE_UP_SATA_TXN<4>";
22"SATA6G_PCH_PCIE_UP_SATA_TXN<5>";
23"SATA6G_PCH_PCIE_UP_SATA_TXP<3>";
24"SATA6G_PCH_PCIE_UP_SATA_TXP<4>";
25"SATA6G_PCH_PCIE_UP_SATA_TXP<6>";
26"SATA6G_PCH_PCIE_UP_SATA_TXN<6>";
27"SATA6G_PCH_PCIE_UP_SATA_TXN<7>";
28"SATA6G_P2_TX_C_DN";
29"SATA6G_P6_TX_C_DP";
30"SATA6G_P0_RX_C_DN";
31"PU_DATAIN1_SATA_0_R";
32"SGPIO_PCH_SATA_CLOCK_R";
33"SGPIO_PCH_SATA_LOAD_R";
34"TP_SGPIO_SATA_LOAD1_R";
35"TP_SGPIO_SATA_CLOCK1_R";
36"SGPIO_PCH_SATA_DOUT0_R";
37"TP_SGPIO_SATA_DATA1_R";
38"TP_FM_QAT_CBL_PRSNT1_N_R";
39"TP_FM_QAT_CBL_PRSNT0_R_N";
40"PU_DATAIN1_SATA_1_R";
41"SATA6G_P5_RX_C_DN";
42"SATA6G_P5_RX_C_DP";
43"SATA6G_P4_RX_C_DP";
44"SATA6G_P1_RX_C_DP";
45"SATA6G_PCH_PCIE_UP_SATA_RXP<1>";
46"SATA6G_PCH_PCIE_UP_SATA_RXP<0>";
47"SATA6G_PCH_PCIE_UP_SATA_RXN<0>";
48"SATA6G_P3_RX_C_DP";
49"SATA6G_P4_RX_C_DN";
50"SATA6G_PCH_PCIE_UP_SATA_RXN<1>";
51"SATA6G_PCH_PCIE_UP_SATA_RXP<5>";
52"SATA6G_PCH_PCIE_UP_SATA_RXN<5>";
53"SATA6G_PCH_PCIE_UP_SATA_RXP<3>";
54"SATA6G_PCH_PCIE_UP_SATA_RXN<3>";
55"SATA6G_PCH_PCIE_UP_SATA_RXP<2>";
56"SATA6G_PCH_PCIE_UP_SATA_RXN<4>";
57"SATA6G_PCH_PCIE_UP_SATA_RXP<6>";
58"SATA6G_PCH_PCIE_UP_SATA_RXN<6>";
59"SATA6G_PCH_PCIE_UP_SATA_RXN<7>";
60"SATA6G_PCH_PCIE_UP_SATA_RXP<7>";
61"SATA6G_P3_TX_C_DP";
62"SATA6G_P3_TX_C_DN";
63"SATA6G_P6_TX_C_DN";
64"SATA6G_P5_TX_C_DN";
65"SATA6G_PCH_PCIE_UP_SATA_TXP<7>";
66"SATA6G_P5_TX_C_DP";
67"SATA6G_PCH_PCIE_UP_SATA_TXP<5>";
68"SATA6G_P0_TX_C_DP";
69"SATA6G_P1_TX_C_DN";
70"SATA6G_PCH_PCIE_UP_SATA_TXP<2>";
71"SATA6G_P7_TX_C_DP";
72"SATA6G_P7_RX_C_DN";
73"SATA6G_PCH_PCIE_UP_SATA_RXP<4>";
74"SATA6G_P6_RX_C_DN";
75"SATA6G_PCH_PCIE_UP_SATA_RXN<2>";
76"SATA6G_P6_RX_C_DP";
77"SATA6G_P2_TX_C_DP";
78"PD_SATA0_CONTROLLER_TYPE_R";
79"SATA6G_P0_TX_C_DN";
80"SATA6G_P3_RX_C_DN";
81"SATA6G_P2_RX_C_DN";
82"SATA6G_P1_TX_C_DP";
83"SATA6G_P0_RX_C_DP";
84"SATA6G_PCH_PCIE_UP_SATA_TXP<1>";
85"SATA6G_P4_TX_C_DN";
86"SATA6G_P2_RX_C_DP";
%"GND"
"1","(-1150,1425)","0","mstr_symbols","I103";
;
VOLTAGE"0.0V"
ROOM"ST_SATA"
BOM_COST"ST_SATA"
SIZE"1B"
CDS_LIB"mstr_symbols"
BODY_TYPE"PLUMBING"
HDL_POWER"GND";
"A\NAC"5;
%"GND"
"1","(-2925,1450)","0","mstr_symbols","I162";
;
VOLTAGE"0.0V"
ROOM"ST_SATA"
SIZE"1B"
BOM_COST"ST_SATA"
CDS_LIB"mstr_symbols"
BODY_TYPE"PLUMBING"
HDL_POWER"GND";
"A\NAC"6;
%"CONN72_G97614002_A"
"1","(-2025,3100)","0","mstr_conn","I163";
;
CDS_SEC"1"
LOCATION"J8A1"
PART_NUMBER"G97614-002"
MATERIAL"CONN"
PACK_TYPE"CP"
ROOM"ST_SATA"
CDS_LOCATION"J8A1"
SEC"1"
SEC_TYPE"CP"
CDS_LIB"mstr_conn"
BOM_COST"ST_SATA";
"GND<23>"
$PN"1A3"6;
"RXA0_DP"
$PN"1B4"83;
"RXA3_DN"
$PN"1A8"80;
"TXB0_DP"
$PN"2D4"11;
"RXB1_DN"
$PN"2A5"41;
"GND<11>"
$PN"2A3"6;
"GND<22>"
$PN"1A6"6;
"GND<21>"
$PN"1A9"6;
"GND<18>"
$PN"1B9"6;
"GND<17>"
$PN"1C3"5;
"GND<16>"
$PN"1C6"5;
"GND<15>"
$PN"1C9"5;
"GND<14>"
$PN"1D3"5;
"GND<13>"
$PN"1D6"5;
"GND<12>"
$PN"1D9"5;
"GND<9>"
$PN"2A9"6;
"GND<8>"
$PN"2B3"6;
"GND<7>"
$PN"2B6"6;
"GND<6>"
$PN"2B9"6;
"GND<5>"
$PN"2C3"5;
"GND<4>"
$PN"2C6"5;
"GND<3>"
$PN"2C9"5;
"GND<2>"
$PN"2D3"5;
"GND<1>"
$PN"2D6"5;
"GND<0>"
$PN"2D9"5;
"RXA0_DN"
$PN"1B5"30;
"RXA1_DN"
$PN"1A5"15;
"RXA1_DP"
$PN"1A4"44;
"RXA2_DN"
$PN"1B8"81;
"RXA3_DP"
$PN"1A7"48;
"RXB1_DP"
$PN"2A4"42;
"RXB2_DN"
$PN"2B8"74;
"RXB2_DP"
$PN"2B7"76;
"RXB3_DN"
$PN"2A8"72;
"RXB3_DP"
$PN"2A7"13;
"SIDEBANDA_0"
$PN"1A2"32;
"SIDEBANDA_1"
$PN"1B2"33;
"SIDEBANDA_2"
$PN"1C2"5;
"SIDEBANDA_5"
$PN"1D1"31;
"SIDEBANDA_6"
$PN"1D2"78;
"SIDEBANDB_3"
$PN"2B1"6;
"SIDEBANDB_4"
$PN"2C1"37;
"SIDEBANDB_5"
$PN"2D1"40;
"SIDEBANDB_7"
$PN"2A1"38;
"TXA0_DN"
$PN"1D5"79;
"TXA0_DP"
$PN"1D4"68;
"TXA1_DN"
$PN"1C5"69;
"TXA1_DP"
$PN"1C4"82;
"TXA2_DN"
$PN"1D8"28;
"TXA2_DP"
$PN"1D7"77;
"TXA3_DN"
$PN"1C8"62;
"TXA3_DP"
$PN"1C7"61;
"TXB0_DN"
$PN"2D5"85;
"TXB1_DN"
$PN"2C5"64;
"TXB1_DP"
$PN"2C4"66;
"TXB2_DN"
$PN"2D8"63;
"TXB2_DP"
$PN"2D7"29;
"TXB3_DN"
$PN"2C8"12;
"TXB3_DP"
$PN"2C7"71;
"GND<19>"
$PN"1B6"6;
"GND<10>"
$PN"2A6"6;
"SIDEBANDA_4"
$PN"1C1"36;
"RXB0_DN"
$PN"2B5"49;
"RXB0_DP"
$PN"2B4"43;
"GND<20>"
$PN"1B3"6;
"RXA2_DP"
$PN"1B7"86;
"SIDEBANDA_7"
$PN"1A1"39;
"SIDEBANDA_3"
$PN"1B1"6;
"SIDEBANDB_1"
$PN"2B2"34;
"SIDEBANDB_0"
$PN"2A2"35;
"SIDEBANDB_2"
$PN"2C2"5;
"SIDEBANDB_6"
$PN"2D2"14;
%"CAP_A"
"2","(-4900,3550)","0","dev_discrete","I165";
;
LOCATION"C2L13"
PART_NUMBER"A36096-045"
VALUE"0.01UF"
TOLERANCE"10%"
PACK_TYPE"0402V"
VOLTAGE"25V"
MATERIAL"X7R"
ROOM"ST_SATA"
CDS_LOCATION"C2L13"
BOM_COST"ST_SATA"
CDS_LIB"dev_discrete"
CDS_SEC"1"
SEC_TYPE"0402V"
SEC"1";
"A"
$PN"1"75;
"B"
$PN"2"81;
%"CAP_A"
"2","(-4850,4050)","0","dev_discrete","I166";
;
LOCATION"C2L6"
PART_NUMBER"A36096-045"
VALUE"0.01UF"
TOLERANCE"10%"
PACK_TYPE"0402V"
VOLTAGE"25V"
MATERIAL"X7R"
ROOM"ST_SATA"
SEC"1"
SEC_TYPE"0402V"
CDS_SEC"1"
CDS_LIB"dev_discrete"
BOM_COST"ST_SATA"
CDS_LOCATION"C2L6";
"A"
$PN"1"50;
"B"
$PN"2"15;
%"CAP_A"
"2","(-4575,4550)","0","dev_discrete","I172";
;
LOCATION"C2L19"
VALUE"0.01UF"
TOLERANCE"10%"
PACK_TYPE"0402V"
VOLTAGE"25V"
MATERIAL"X7R"
PART_NUMBER"A36096-045"
ROOM"ST_SATA"
CDS_LOCATION"C2L19"
BOM_COST"ST_SATA"
CDS_LIB"dev_discrete"
CDS_SEC"1"
SEC_TYPE"0402V"
SEC"1";
"A"
$PN"1"46;
"B"
$PN"2"83;
%"CAP_A"
"2","(-4575,4200)","0","dev_discrete","I173";
;
PART_NUMBER"A36096-045"
VALUE"0.01UF"
TOLERANCE"10%"
PACK_TYPE"0402V"
VOLTAGE"25V"
MATERIAL"X7R"
LOCATION"C2L10"
ROOM"ST_SATA"
SEC"1"
SEC_TYPE"0402V"
CDS_SEC"1"
CDS_LIB"dev_discrete"
BOM_COST"ST_SATA"
CDS_LOCATION"C2L10";
"A"
$PN"1"45;
"B"
$PN"2"44;
%"CAP_A"
"2","(-4850,4400)","0","dev_discrete","I174";
;
PACK_TYPE"0402V"
LOCATION"C2L17"
PART_NUMBER"A36096-045"
VALUE"0.01UF"
TOLERANCE"10%"
VOLTAGE"25V"
MATERIAL"X7R"
ROOM"ST_SATA"
CDS_LOCATION"C2L17"
BOM_COST"ST_SATA"
CDS_LIB"dev_discrete"
CDS_SEC"1"
SEC_TYPE"0402V"
SEC"1";
"A"
$PN"1"47;
"B"
$PN"2"30;
%"TAP"
"6","(-5250,4400)","0","mstr_standard","I175";
;
CDS_LIB"mstr_standard"
BODY_TYPE"PLUMBING"
HDL_TAP"TRUE";
"B \NAC \NWC"2;
"S \NAC"
BN"0"47;
%"TAP"
"6","(-5400,4550)","0","mstr_standard","I176";
;
CDS_LIB"mstr_standard"
BODY_TYPE"PLUMBING"
HDL_TAP"TRUE";
"B \NAC \NWC"3;
"S \NAC"
BN"0"46;
%"TAP"
"6","(-5400,4200)","0","mstr_standard","I177";
;
CDS_LIB"mstr_standard"
BODY_TYPE"PLUMBING"
HDL_TAP"TRUE";
"B \NAC \NWC"3;
"S \NAC"
BN"1"45;
%"CAP_A"
"2","(-4575,3700)","0","dev_discrete","I191";
;
LOCATION"C2L15"
PART_NUMBER"A36096-045"
VALUE"0.01UF"
TOLERANCE"10%"
VOLTAGE"25V"
MATERIAL"X7R"
PACK_TYPE"0402V"
ROOM"ST_SATA"
CDS_LOCATION"C2L15"
BOM_COST"ST_SATA"
CDS_LIB"dev_discrete"
CDS_SEC"1"
SEC_TYPE"0402V"
SEC"1";
"A"
$PN"1"55;
"B"
$PN"2"86;
%"CAP_A"
"2","(-4575,3350)","0","dev_discrete","I192";
;
LOCATION"C2L4"
PART_NUMBER"A36096-045"
TOLERANCE"10%"
PACK_TYPE"0402V"
VOLTAGE"25V"
MATERIAL"X7R"
VALUE"0.01UF"
ROOM"ST_SATA"
SEC"1"
SEC_TYPE"0402V"
CDS_SEC"1"
CDS_LIB"dev_discrete"
BOM_COST"ST_SATA"
CDS_LOCATION"C2L4";
"A"
$PN"1"53;
"B"
$PN"2"48;
%"CAP_A"
"2","(-4900,3200)","0","dev_discrete","I194";
;
LOCATION"C2L3"
VALUE"0.01UF"
TOLERANCE"10%"
PACK_TYPE"0402V"
VOLTAGE"25V"
MATERIAL"X7R"
PART_NUMBER"A36096-045"
ROOM"ST_SATA"
CDS_LOCATION"C2L3"
BOM_COST"ST_SATA"
CDS_LIB"dev_discrete"
CDS_SEC"1"
SEC_TYPE"0402V"
SEC"1";
"A"
$PN"1"54;
"B"
$PN"2"80;
%"CAP_A"
"2","(-4600,2900)","0","dev_discrete","I195";
;
LOCATION"C2L20"
PART_NUMBER"A36096-045"
VALUE"0.01UF"
TOLERANCE"10%"
PACK_TYPE"0402V"
VOLTAGE"25V"
MATERIAL"X7R"
ROOM"ST_SATA"
CDS_LOCATION"C2L20"
BOM_COST"ST_SATA"
CDS_LIB"dev_discrete"
CDS_SEC"1"
SEC_TYPE"0402V"
SEC"1";
"A"
$PN"1"73;
"B"
$PN"2"43;
%"CAP_A"
"2","(-4575,2550)","0","dev_discrete","I196";
;
TOLERANCE"10%"
PACK_TYPE"0402V"
VOLTAGE"25V"
MATERIAL"X7R"
VALUE"0.01UF"
PART_NUMBER"A36096-045"
LOCATION"C2L12"
ROOM"ST_SATA"
SEC"1"
SEC_TYPE"0402V"
CDS_SEC"1"
CDS_LIB"dev_discrete"
BOM_COST"ST_SATA"
CDS_LOCATION"C2L12";
"A"
$PN"1"51;
"B"
$PN"2"42;
%"CAP_A"
"2","(-4950,2750)","0","dev_discrete","I197";
;
VALUE"0.01UF"
TOLERANCE"10%"
PACK_TYPE"0402V"
VOLTAGE"25V"
MATERIAL"X7R"
PART_NUMBER"A36096-045"
LOCATION"C2L18"
ROOM"ST_SATA"
CDS_LOCATION"C2L18"
BOM_COST"ST_SATA"
CDS_LIB"dev_discrete"
CDS_SEC"1"
SEC_TYPE"0402V"
SEC"1";
"A"
$PN"1"56;
"B"
$PN"2"49;
%"TAP"
"6","(-5250,3550)","0","mstr_standard","I198";
;
CDS_LIB"mstr_standard"
BODY_TYPE"PLUMBING"
HDL_TAP"TRUE";
"B \NAC \NWC"2;
"S \NAC"
BN"2"75;
%"TAP"
"6","(-5400,3700)","0","mstr_standard","I199";
;
CDS_LIB"mstr_standard"
BODY_TYPE"PLUMBING"
HDL_TAP"TRUE";
"B \NAC \NWC"3;
"S \NAC"
BN"2"55;
%"TAP"
"6","(-5400,3350)","0","mstr_standard","I200";
;
CDS_LIB"mstr_standard"
BODY_TYPE"PLUMBING"
HDL_TAP"TRUE";
"B \NAC \NWC"3;
"S \NAC"
BN"3"53;
%"TAP"
"6","(-5250,3200)","0","mstr_standard","I201";
;
CDS_LIB"mstr_standard"
BODY_TYPE"PLUMBING"
HDL_TAP"TRUE";
"B \NAC \NWC"2;
"S \NAC"
BN"3"54;
%"TAP"
"6","(-5400,2900)","0","mstr_standard","I202";
;
CDS_LIB"mstr_standard"
BODY_TYPE"PLUMBING"
HDL_TAP"TRUE";
"B \NAC \NWC"3;
"S \NAC"
BN"4"73;
%"TAP"
"6","(-5400,2550)","0","mstr_standard","I203";
;
CDS_LIB"mstr_standard"
BODY_TYPE"PLUMBING"
HDL_TAP"TRUE";
"B \NAC \NWC"3;
"S \NAC"
BN"5"51;
%"TAP"
"6","(-5250,2750)","0","mstr_standard","I204";
;
CDS_LIB"mstr_standard"
BODY_TYPE"PLUMBING"
HDL_TAP"TRUE";
"B \NAC \NWC"2;
"S \NAC"
BN"4"56;
%"CAP_A"
"2","(-4575,2050)","0","dev_discrete","I205";
;
LOCATION"C2L16"
PART_NUMBER"A36096-045"
TOLERANCE"10%"
PACK_TYPE"0402V"
VOLTAGE"25V"
MATERIAL"X7R"
VALUE"0.01UF"
ROOM"ST_SATA"
CDS_LOCATION"C2L16"
BOM_COST"ST_SATA"
CDS_LIB"dev_discrete"
CDS_SEC"1"
SEC_TYPE"0402V"
SEC"1";
"A"
$PN"1"57;
"B"
$PN"2"76;
%"CAP_A"
"2","(-4575,1700)","0","dev_discrete","I206";
;
LOCATION"C2L7"
PART_NUMBER"A36096-045"
VALUE"0.01UF"
TOLERANCE"10%"
VOLTAGE"25V"
MATERIAL"X7R"
PACK_TYPE"0402V"
ROOM"ST_SATA"
SEC"1"
SEC_TYPE"0402V"
CDS_SEC"1"
CDS_LIB"dev_discrete"
BOM_COST"ST_SATA"
CDS_LOCATION"C2L7";
"A"
$PN"1"60;
"B"
$PN"2"13;
%"CAP_A"
"2","(-4950,2400)","0","dev_discrete","I207";
;
LOCATION"C2L9"
VALUE"0.01UF"
TOLERANCE"10%"
PACK_TYPE"0402V"
VOLTAGE"25V"
MATERIAL"X7R"
PART_NUMBER"A36096-045"
ROOM"ST_SATA"
CDS_LOCATION"C2L9"
BOM_COST"ST_SATA"
CDS_LIB"dev_discrete"
CDS_SEC"1"
SEC_TYPE"0402V"
SEC"1";
"A"
$PN"1"52;
"B"
$PN"2"41;
%"CAP_A"
"2","(-4975,1850)","0","dev_discrete","I208";
;
LOCATION"C2L14"
PART_NUMBER"A36096-045"
VALUE"0.01UF"
TOLERANCE"10%"
VOLTAGE"25V"
PACK_TYPE"0402V"
MATERIAL"X7R"
ROOM"ST_SATA"
CDS_LOCATION"C2L14"
BOM_COST"ST_SATA"
CDS_LIB"dev_discrete"
CDS_SEC"1"
SEC_TYPE"0402V"
SEC"1";
"A"
$PN"1"58;
"B"
$PN"2"74;
%"CAP_A"
"2","(-4975,1500)","0","dev_discrete","I209";
;
VALUE"0.01UF"
TOLERANCE"10%"
PACK_TYPE"0402V"
VOLTAGE"25V"
MATERIAL"X7R"
PART_NUMBER"A36096-045"
LOCATION"C2L5"
ROOM"ST_SATA"
CDS_LOCATION"C2L5"
BOM_COST"ST_SATA"
CDS_LIB"dev_discrete"
CDS_SEC"1"
SEC_TYPE"0402V"
SEC"1";
"A"
$PN"1"59;
"B"
$PN"2"72;
%"TAP"
"6","(-5250,2400)","0","mstr_standard","I210";
;
CDS_LIB"mstr_standard"
BODY_TYPE"PLUMBING"
HDL_TAP"TRUE";
"B \NAC \NWC"2;
"S \NAC"
BN"5"52;
%"TAP"
"6","(-5400,2050)","0","mstr_standard","I211";
;
CDS_LIB"mstr_standard"
BODY_TYPE"PLUMBING"
HDL_TAP"TRUE";
"B \NAC \NWC"3;
"S \NAC"
BN"6"57;
%"TAP"
"6","(-5400,1700)","0","mstr_standard","I212";
;
CDS_LIB"mstr_standard"
BODY_TYPE"PLUMBING"
HDL_TAP"TRUE";
"B \NAC \NWC"3;
"S \NAC"
BN"7"60;
%"TAP"
"6","(-5250,1850)","0","mstr_standard","I213";
;
CDS_LIB"mstr_standard"
BODY_TYPE"PLUMBING"
HDL_TAP"TRUE";
"B \NAC \NWC"2;
"S \NAC"
BN"6"58;
%"TAP"
"6","(-5250,1500)","0","mstr_standard","I214";
;
CDS_LIB"mstr_standard"
BODY_TYPE"PLUMBING"
HDL_TAP"TRUE";
"B \NAC \NWC"2;
"S \NAC"
BN"7"59;
%"TAP"
"1","(1300,1550)","0","mstr_standard","I215";
;
CDS_LIB"mstr_standard"
BODY_TYPE"PLUMBING"
HDL_TAP"TRUE";
"B \NAC \NWC"4;
"S \NAC"
BN"7"27;
%"TAP"
"1","(1450,4675)","0","mstr_standard","I216";
;
CDS_LIB"mstr_standard"
BODY_TYPE"PLUMBING"
HDL_TAP"TRUE";
"B \NAC \NWC"1;
"S \NAC"
BN"0"18;
%"TAP"
"1","(1450,4325)","0","mstr_standard","I217";
;
CDS_LIB"mstr_standard"
BODY_TYPE"PLUMBING"
HDL_TAP"TRUE";
"B \NAC \NWC"1;
"S \NAC"
BN"1"84;
%"TAP"
"1","(1300,4175)","0","mstr_standard","I218";
;
CDS_LIB"mstr_standard"
BODY_TYPE"PLUMBING"
HDL_TAP"TRUE";
"B \NAC \NWC"4;
"S \NAC"
BN"1"17;
%"TAP"
"1","(1300,4525)","0","mstr_standard","I219";
;
CDS_LIB"mstr_standard"
BODY_TYPE"PLUMBING"
HDL_TAP"TRUE";
"B \NAC \NWC"4;
"S \NAC"
BN"0"16;
%"CAP_A"
"2","(1025,4525)","0","dev_discrete","I220";
;
LOCATION"C2L40"
PART_NUMBER"A36096-045"
VALUE"0.01UF"
TOLERANCE"10%"
PACK_TYPE"0402V"
VOLTAGE"25V"
MATERIAL"X7R"
ROOM"ST_SATA"
CDS_LOCATION"C2L40"
BOM_COST"ST_SATA"
CDS_LIB"dev_discrete"
CDS_SEC"1"
SEC_TYPE"0402V"
SEC"1";
"A"
$PN"1"79;
"B"
$PN"2"16;
%"CAP_A"
"2","(650,4675)","0","dev_discrete","I221";
;
LOCATION"C2L39"
TOLERANCE"10%"
VOLTAGE"25V"
MATERIAL"X7R"
PACK_TYPE"0402V"
VALUE"0.01UF"
PART_NUMBER"A36096-045"
ROOM"ST_SATA"
CDS_LOCATION"C2L39"
BOM_COST"ST_SATA"
CDS_LIB"dev_discrete"
CDS_SEC"1"
SEC_TYPE"0402V"
SEC"1";
"A"
$PN"1"68;
"B"
$PN"2"18;
%"CAP_A"
"2","(650,4325)","0","dev_discrete","I222";
;
TOLERANCE"10%"
PACK_TYPE"0402V"
MATERIAL"X7R"
VOLTAGE"25V"
VALUE"0.01UF"
PART_NUMBER"A36096-045"
LOCATION"C2L43"
ROOM"ST_SATA"
CDS_LOCATION"C2L43"
BOM_COST"ST_SATA"
CDS_LIB"dev_discrete"
CDS_SEC"1"
SEC_TYPE"0402V"
SEC"1";
"A"
$PN"1"82;
"B"
$PN"2"84;
%"CAP_A"
"2","(1025,4175)","0","dev_discrete","I228";
;
LOCATION"C2L44"
PART_NUMBER"A36096-045"
VALUE"0.01UF"
TOLERANCE"10%"
PACK_TYPE"0402V"
VOLTAGE"25V"
MATERIAL"X7R"
ROOM"ST_SATA"
SEC"1"
SEC_TYPE"0402V"
CDS_SEC"1"
CDS_LIB"dev_discrete"
BOM_COST"ST_SATA"
CDS_LOCATION"C2L44";
"A"
$PN"1"69;
"B"
$PN"2"17;
%"TAP"
"1","(1450,3650)","0","mstr_standard","I229";
;
CDS_LIB"mstr_standard"
BODY_TYPE"PLUMBING"
HDL_TAP"TRUE";
"B \NAC \NWC"1;
"S \NAC"
BN"2"70;
%"TAP"
"1","(1450,3300)","0","mstr_standard","I230";
;
CDS_LIB"mstr_standard"
BODY_TYPE"PLUMBING"
HDL_TAP"TRUE";
"B \NAC \NWC"1;
"S \NAC"
BN"3"23;
%"TAP"
"1","(1300,3500)","0","mstr_standard","I231";
;
CDS_LIB"mstr_standard"
BODY_TYPE"PLUMBING"
HDL_TAP"TRUE";
"B \NAC \NWC"4;
"S \NAC"
BN"2"19;
%"TAP"
"1","(1300,3075)","0","mstr_standard","I232";
;
CDS_LIB"mstr_standard"
BODY_TYPE"PLUMBING"
HDL_TAP"TRUE";
"B \NAC \NWC"4;
"S \NAC"
BN"3"20;
%"CAP_A"
"2","(1000,3500)","0","dev_discrete","I233";
;
LOCATION"C2L42"
VALUE"0.01UF"
TOLERANCE"10%"
PACK_TYPE"0402V"
VOLTAGE"25V"
MATERIAL"X7R"
PART_NUMBER"A36096-045"
ROOM"ST_SATA"
CDS_LOCATION"C2L42"
BOM_COST"ST_SATA"
CDS_LIB"dev_discrete"
CDS_SEC"1"
SEC_TYPE"0402V"
SEC"1";
"A"
$PN"1"28;
"B"
$PN"2"19;
%"CAP_A"
"2","(1025,3075)","0","dev_discrete","I234";
;
LOCATION"C2L22"
PART_NUMBER"A36096-045"
VALUE"0.01UF"
TOLERANCE"10%"
PACK_TYPE"0402V"
VOLTAGE"25V"
MATERIAL"X7R"
ROOM"ST_SATA"
CDS_LOCATION"C2L22"
BOM_COST"ST_SATA"
CDS_LIB"dev_discrete"
CDS_SEC"1"
SEC_TYPE"0402V"
SEC"1";
"A"
$PN"1"62;
"B"
$PN"2"20;
%"TAP"
"1","(1450,2925)","0","mstr_standard","I235";
;
CDS_LIB"mstr_standard"
BODY_TYPE"PLUMBING"
HDL_TAP"TRUE";
"B \NAC \NWC"1;
"S \NAC"
BN"4"24;
%"TAP"
"1","(1450,2500)","0","mstr_standard","I236";
;
CDS_LIB"mstr_standard"
BODY_TYPE"PLUMBING"
HDL_TAP"TRUE";
"B \NAC \NWC"1;
"S \NAC"
BN"5"67;
%"TAP"
"1","(1300,2725)","0","mstr_standard","I237";
;
CDS_LIB"mstr_standard"
BODY_TYPE"PLUMBING"
HDL_TAP"TRUE";
"B \NAC \NWC"4;
"S \NAC"
BN"4"21;
%"CAP_A"
"2","(1025,2725)","0","dev_discrete","I238";
;
LOCATION"C2L37"
PART_NUMBER"A36096-045"
VALUE"0.01UF"
TOLERANCE"10%"
PACK_TYPE"0402V"
VOLTAGE"25V"
MATERIAL"X7R"
ROOM"ST_SATA"
CDS_LOCATION"C2L37"
BOM_COST"ST_SATA"
CDS_LIB"dev_discrete"
CDS_SEC"1"
SEC_TYPE"0402V"
SEC"1";
"A"
$PN"1"85;
"B"
$PN"2"21;
%"CAP_A"
"2","(650,2925)","0","dev_discrete","I239";
;
LOCATION"C2L47"
PART_NUMBER"A36096-045"
VALUE"0.01UF"
TOLERANCE"10%"
PACK_TYPE"0402V"
VOLTAGE"25V"
MATERIAL"X7R"
ROOM"ST_SATA"
SEC"1"
SEC_TYPE"0402V"
CDS_SEC"1"
CDS_LIB"dev_discrete"
BOM_COST"ST_SATA"
CDS_LOCATION"C2L47";
"A"
$PN"1"11;
"B"
$PN"2"24;
%"CAP_A"
"2","(650,2500)","0","dev_discrete","I240";
;
LOCATION"C2L27"
TOLERANCE"10%"
PACK_TYPE"0402V"
MATERIAL"X7R"
VOLTAGE"25V"
VALUE"0.01UF"
PART_NUMBER"A36096-045"
ROOM"ST_SATA"
CDS_LOCATION"C2L27"
BOM_COST"ST_SATA"
CDS_LIB"dev_discrete"
CDS_SEC"1"
SEC_TYPE"0402V"
SEC"1";
"A"
$PN"1"66;
"B"
$PN"2"67;
%"CAP_A"
"2","(625,3300)","0","dev_discrete","I241";
;
LOCATION"C2L23"
PART_NUMBER"A36096-045"
VALUE"0.01UF"
TOLERANCE"10%"
PACK_TYPE"0402V"
VOLTAGE"25V"
MATERIAL"X7R"
ROOM"ST_SATA"
CDS_LOCATION"C2L23"
BOM_COST"ST_SATA"
CDS_LIB"dev_discrete"
CDS_SEC"1"
SEC_TYPE"0402V"
SEC"1";
"A"
$PN"1"61;
"B"
$PN"2"23;
%"CAP_A"
"2","(625,3650)","0","dev_discrete","I242";
;
LOCATION"C2L41"
VALUE"0.01UF"
TOLERANCE"10%"
PACK_TYPE"0402V"
MATERIAL"X7R"
VOLTAGE"25V"
PART_NUMBER"A36096-045"
ROOM"ST_SATA"
SEC"1"
SEC_TYPE"0402V"
CDS_SEC"1"
CDS_LIB"dev_discrete"
BOM_COST"ST_SATA"
CDS_LOCATION"C2L41";
"A"
$PN"1"77;
"B"
$PN"2"70;
%"TAP"
"1","(1300,2350)","0","mstr_standard","I251";
;
CDS_LIB"mstr_standard"
BODY_TYPE"PLUMBING"
HDL_TAP"TRUE";
"B \NAC \NWC"4;
"S \NAC"
BN"5"22;
%"TAP"
"1","(1450,2050)","0","mstr_standard","I252";
;
CDS_LIB"mstr_standard"
BODY_TYPE"PLUMBING"
HDL_TAP"TRUE";
"B \NAC \NWC"1;
"S \NAC"
BN"6"25;
%"TAP"
"1","(1450,1700)","0","mstr_standard","I253";
;
CDS_LIB"mstr_standard"
BODY_TYPE"PLUMBING"
HDL_TAP"TRUE";
"B \NAC \NWC"1;
"S \NAC"
BN"7"65;
%"TAP"
"1","(1300,1900)","0","mstr_standard","I254";
;
CDS_LIB"mstr_standard"
BODY_TYPE"PLUMBING"
HDL_TAP"TRUE";
"B \NAC \NWC"4;
"S \NAC"
BN"6"26;
%"CAP_A"
"2","(1025,2350)","0","dev_discrete","I255";
;
LOCATION"C2L26"
PART_NUMBER"A36096-045"
VALUE"0.01UF"
TOLERANCE"10%"
PACK_TYPE"0402V"
VOLTAGE"25V"
MATERIAL"X7R"
ROOM"ST_SATA"
CDS_LOCATION"C2L26"
BOM_COST"ST_SATA"
CDS_LIB"dev_discrete"
CDS_SEC"1"
SEC_TYPE"0402V"
SEC"1";
"A"
$PN"1"64;
"B"
$PN"2"22;
%"CAP_A"
"2","(1050,1900)","0","dev_discrete","I256";
;
LOCATION"C2L38"
TOLERANCE"10%"
VOLTAGE"25V"
MATERIAL"X7R"
PART_NUMBER"A36096-045"
VALUE"0.01UF"
PACK_TYPE"0402V"
ROOM"ST_SATA"
CDS_LOCATION"C2L38"
BOM_COST"ST_SATA"
CDS_LIB"dev_discrete"
CDS_SEC"1"
SEC_TYPE"0402V"
SEC"1";
"A"
$PN"1"63;
"B"
$PN"2"26;
%"CAP_A"
"2","(650,2050)","0","dev_discrete","I257";
;
PART_NUMBER"A36096-045"
VALUE"0.01UF"
TOLERANCE"10%"
PACK_TYPE"0402V"
VOLTAGE"25V"
MATERIAL"X7R"
LOCATION"C2L48"
ROOM"ST_SATA"
CDS_LOCATION"C2L48"
BOM_COST"ST_SATA"
CDS_LIB"dev_discrete"
CDS_SEC"1"
SEC_TYPE"0402V"
SEC"1";
"A"
$PN"1"29;
"B"
$PN"2"25;
%"CAP_A"
"2","(650,1700)","0","dev_discrete","I258";
;
VALUE"0.01UF"
TOLERANCE"10%"
VOLTAGE"25V"
MATERIAL"X7R"
LOCATION"C2L24"
PACK_TYPE"0402V"
PART_NUMBER"A36096-045"
ROOM"ST_SATA"
SEC"1"
SEC_TYPE"0402V"
CDS_SEC"1"
CDS_LIB"dev_discrete"
BOM_COST"ST_SATA"
CDS_LOCATION"C2L24";
"A"
$PN"1"71;
"B"
$PN"2"65;
%"CAP_A"
"2","(1050,1550)","0","dev_discrete","I259";
;
LOCATION"C2L21"
PART_NUMBER"A36096-045"
TOLERANCE"10%"
PACK_TYPE"0402V"
VOLTAGE"25V"
MATERIAL"X7R"
VALUE"0.01UF"
ROOM"ST_SATA"
CDS_LOCATION"C2L21"
BOM_COST"ST_SATA"
CDS_LIB"dev_discrete"
CDS_SEC"1"
SEC_TYPE"0402V"
SEC"1";
"A"
$PN"1"12;
"B"
$PN"2"27;
%"P3V3"
"1","(-4075,2300)","0","mstr_symbols","I260";
;
VOLTAGE"3.3V"
ROOM"ST_SATA"
CDS_LIB"mstr_symbols"
BOM_COST"ST_SATA"
SIZE"1B"
BODY_TYPE"PLUMBING"
HDL_POWER"P3V3";
"G\NAC"7;
%"RES"
"1","(-3900,2200)","0","mstr_discrete","I261";
;
CDS_SEC"1"
LOCATION"R2L23"
PART_NUMBER"G21796-001"
VALUE"2.0K"
TOLERANCE"1%"
PACK_TYPE"0402"
MATERIAL"CHIP"
WATTAGE"1/16W"
ROOM"ST_SATA"
SEC_TYPE"0402"
CDS_LIB"mstr_discrete"
BOM_COST"ST_SATA"
SEC"1"
CDS_LOCATION"R2L23";
"B"
$PN"2"40;
"A"
$PN"1"7;
%"P3V3"
"1","(-3900,5025)","0","mstr_symbols","I262";
;
VOLTAGE"3.3V"
ROOM"ST_SATA"
CDS_LIB"mstr_symbols"
BOM_COST"ST_SATA"
SIZE"1B"
BODY_TYPE"PLUMBING"
HDL_POWER"P3V3";
"G\NAC"8;
%"RES"
"2","(-3900,4675)","0","mstr_discrete","I263";
;
CDS_SEC"1"
LOCATION"R2L21"
PART_NUMBER"G21796-001"
VALUE"2.0K"
TOLERANCE"1%"
PACK_TYPE"0402"
MATERIAL"CHIP"
WATTAGE"1/16W"
ROOM"ST_SATA"
SEC_TYPE"0402"
CDS_LIB"mstr_discrete"
BOM_COST"ST_SATA"
SEC"1"
CDS_LOCATION"R2L21";
"A"
$PN"1"8;
"B"
$PN"2"31;
%"RES"
"2","(1625,2000)","0","mstr_discrete","I264";
;
CDS_SEC"1"
LOCATION"R2L22"
PART_NUMBER"G21796-026"
VALUE"1.00K"
TOLERANCE"1%"
PACK_TYPE"0402"
MATERIAL"CHIP"
WATTAGE"1/16W"
ROOM"ST_SATA"
SEC_TYPE"0402"
BOM_COST"ST_SATA"
CDS_LIB"mstr_discrete"
SEC"1"
CDS_LOCATION"R2L22";
"A"
$PN"1"14;
"B"
$PN"2"9;
%"GND"
"1","(1625,1700)","0","mstr_symbols","I265";
;
VOLTAGE"0.0V"
ROOM"ST_SATA"
BOM_COST"ST_SATA"
SIZE"1B"
CDS_LIB"mstr_symbols"
BODY_TYPE"PLUMBING"
HDL_POWER"GND";
"A\NAC"9;
%"RES"
"2","(1675,3500)","0","mstr_discrete","I266";
;
CDS_SEC"1"
LOCATION"R2L18"
PART_NUMBER"G21796-026"
VALUE"1.00K"
TOLERANCE"1%"
PACK_TYPE"0402"
MATERIAL"CHIP"
WATTAGE"1/16W"
ROOM"ST_SATA"
SEC_TYPE"0402"
CDS_LIB"mstr_discrete"
BOM_COST"ST_SATA"
SEC"1"
CDS_LOCATION"R2L18";
"A"
$PN"1"78;
"B"
$PN"2"10;
%"GND"
"1","(1675,3275)","0","mstr_symbols","I267";
;
VOLTAGE"0.0V"
ROOM"ST_SATA"
CDS_LIB"mstr_symbols"
BOM_COST"ST_SATA"
SIZE"1B"
BODY_TYPE"PLUMBING"
HDL_POWER"GND";
"A\NAC"10;
%"TAP"
"6","(-5250,4050)","0","mstr_standard","I271";
;
CDS_LIB"mstr_standard"
BODY_TYPE"PLUMBING"
HDL_TAP"TRUE";
"B \NAC \NWC"2;
"S \NAC"
BN"1"50;
END.
